(kicad_pcb
	(version 20260206)
	(generator "pcbnew")
	(generator_version "10.0")
	(general
		(thickness 1.6)
		(legacy_teardrops no)
	)
	(paper "A4")
	(title_block
		(title "01162023_DA0F0TEBIF0_F0T_Expander_BD_F_brd_V02_OCP.brd")
		(comment 1 "Grand Teton / footprints 1342-1346 of 9728")
	)
	(layers
		(0 "F.Cu" signal "TOP")
		(4 "In1.Cu" signal "GND")
		(6 "In2.Cu" signal "VCC")
		(8 "In3.Cu" signal "VCC1")
		(10 "In4.Cu" signal "GND1")
		(12 "In5.Cu" signal "IN1")
		(14 "In6.Cu" signal "GND2")
		(16 "In7.Cu" signal "IN2")
		(18 "In8.Cu" signal "GND3")
		(20 "In9.Cu" signal "IN3")
		(22 "In10.Cu" signal "GND4")
		(24 "In11.Cu" signal "IN4")
		(26 "In12.Cu" signal "GND5")
		(28 "In13.Cu" signal "IN5")
		(30 "In14.Cu" signal "GND6")
		(32 "In15.Cu" signal "IN6")
		(34 "In16.Cu" signal "GND7")
		(2 "B.Cu" signal "BOTTOM")
		(9 "F.Adhes" user "F.Adhesive")
		(11 "B.Adhes" user "B.Adhesive")
		(13 "F.Paste" user "Package Geometry/Pastemask Top")
		(15 "B.Paste" user "Package Geometry/Pastemask Bottom")
		(5 "F.SilkS" user "Ref Des/Silkscreen Top")
		(7 "B.SilkS" user "Ref Des/Silkscreen Bottom")
		(1 "F.Mask" user "Board Geometry/Soldermask Top")
		(3 "B.Mask" user "Board Geometry/Soldermask Bottom")
		(17 "Dwgs.User" user "User.Drawings")
		(19 "Cmts.User" user "User.Comments")
		(21 "Eco1.User" user "User.Eco1")
		(23 "Eco2.User" user "User.Eco2")
		(25 "Edge.Cuts" user "Board Geometry/Outline")
		(27 "Margin" user)
		(31 "F.CrtYd" user "Package Geometry/Place Bound Top")
		(29 "B.CrtYd" user "Package Geometry/Place Bound Bottom")
		(35 "F.Fab" user "Ref Des/Assembly Top")
		(33 "B.Fab" user "Ref Des/Assembly Bottom")
	)
	(footprint ""
		(layer "F.Cu")
		(at 336.042 -178.943 180)
		(property "Reference" "R4740"
			(at 0 0 180)
			(layer "F.SilkS")
			(hide yes)
			(effects
				(font
					(size 1.27 1.27)
				)
			)
		)
		(property "Value" ""
			(at 0 0 180)
			(layer "F.Fab")
			(effects
				(font
					(size 1.27 1.27)
				)
			)
		)
		(duplicate_pad_numbers_are_jumpers no)
		(fp_line
			(start 0.7874 0.4064)
			(end -0.7874 0.4064)
			(stroke
				(width 0.1524)
				(type default)
			)
			(layer "F.SilkS")
		)
		(fp_line
			(start 0.7874 -0.4064)
			(end 0.7874 0.4064)
			(stroke
				(width 0.1524)
				(type default)
			)
			(layer "F.SilkS")
		)
		(fp_line
			(start -0.7874 0.4064)
			(end -0.7874 -0.4064)
			(stroke
				(width 0.1524)
				(type default)
			)
			(layer "F.SilkS")
		)
		(fp_line
			(start -0.7874 -0.4064)
			(end 0.7874 -0.4064)
			(stroke
				(width 0.1524)
				(type default)
			)
			(layer "F.SilkS")
		)
		(fp_line
			(start 0.67945 0.3048)
			(end 0.120396 0.3048)
			(stroke
				(width 0.1)
				(type default)
			)
			(layer "F.Fab")
		)
		(fp_line
			(start 0.67945 -0.3048)
			(end 0.67945 0.3048)
			(stroke
				(width 0.1)
				(type default)
			)
			(layer "F.Fab")
		)
		(fp_line
			(start 0.12065 -0.2794)
			(end 0.12065 -0.3048)
			(stroke
				(width 0.1)
				(type default)
			)
			(layer "F.Fab")
		)
		(fp_line
			(start 0.12065 -0.3048)
			(end 0.67945 -0.3048)
			(stroke
				(width 0.1)
				(type default)
			)
			(layer "F.Fab")
		)
		(fp_line
			(start 0.120396 0.3048)
			(end 0.120396 0.2794)
			(stroke
				(width 0.1)
				(type default)
			)
			(layer "F.Fab")
		)
		(fp_line
			(start 0.120396 0.2794)
			(end -0.12065 0.2794)
			(stroke
				(width 0.1)
				(type default)
			)
			(layer "F.Fab")
		)
		(fp_line
			(start -0.12065 0.3048)
			(end -0.67945 0.3048)
			(stroke
				(width 0.1)
				(type default)
			)
			(layer "F.Fab")
		)
		(fp_line
			(start -0.12065 0.2794)
			(end -0.12065 0.3048)
			(stroke
				(width 0.1)
				(type default)
			)
			(layer "F.Fab")
		)
		(fp_line
			(start -0.12065 -0.2794)
			(end 0.12065 -0.2794)
			(stroke
				(width 0.1)
				(type default)
			)
			(layer "F.Fab")
		)
		(fp_line
			(start -0.12065 -0.305054)
			(end -0.12065 -0.2794)
			(stroke
				(width 0.1)
				(type default)
			)
			(layer "F.Fab")
		)
		(fp_line
			(start -0.67945 0.3048)
			(end -0.67945 -0.305054)
			(stroke
				(width 0.1)
				(type default)
			)
			(layer "F.Fab")
		)
		(fp_line
			(start -0.67945 -0.305054)
			(end -0.12065 -0.305054)
			(stroke
				(width 0.1)
				(type default)
			)
			(layer "F.Fab")
		)
		(pad "1" smd circle
			(at -0.40005 0 180)
			(size 0 0)
			(layers "F.Cu" "F.Mask" "F.Paste")
			(net "SSD9_PEX_PWR_EN_R")
		)
		(pad "2" smd circle
			(at 0.40005 0 180)
			(size 0 0)
			(layers "F.Cu" "F.Mask" "F.Paste")
			(net "GND")
		)
	)
	(footprint ""
		(layer "F.Cu")
		(at 43.926506 -25.432004 -90)
		(property "Reference" "C966"
			(at 0 0 270)
			(layer "F.SilkS")
			(hide yes)
			(effects
				(font
					(size 1.27 1.27)
				)
			)
		)
		(property "Value" ""
			(at 0 0 270)
			(layer "F.Fab")
			(effects
				(font
					(size 1.27 1.27)
				)
			)
		)
		(duplicate_pad_numbers_are_jumpers no)
		(fp_line
			(start -0.7874 0.4064)
			(end -0.7874 -0.4064)
			(stroke
				(width 0.1524)
				(type default)
			)
			(layer "F.SilkS")
		)
		(fp_line
			(start 0.7874 0.4064)
			(end -0.7874 0.4064)
			(stroke
				(width 0.1524)
				(type default)
			)
			(layer "F.SilkS")
		)
		(fp_line
			(start -0.7874 -0.4064)
			(end 0.7874 -0.4064)
			(stroke
				(width 0.1524)
				(type default)
			)
			(layer "F.SilkS")
		)
		(fp_line
			(start 0.7874 -0.4064)
			(end 0.7874 0.4064)
			(stroke
				(width 0.1524)
				(type default)
			)
			(layer "F.SilkS")
		)
		(fp_line
			(start -0.67945 0.3048)
			(end -0.67945 -0.305054)
			(stroke
				(width 0.1)
				(type default)
			)
			(layer "F.Fab")
		)
		(fp_line
			(start -0.12065 0.3048)
			(end -0.67945 0.3048)
			(stroke
				(width 0.1)
				(type default)
			)
			(layer "F.Fab")
		)
		(fp_line
			(start 0.120396 0.3048)
			(end 0.120396 0.2794)
			(stroke
				(width 0.1)
				(type default)
			)
			(layer "F.Fab")
		)
		(fp_line
			(start 0.67945 0.3048)
			(end 0.120396 0.3048)
			(stroke
				(width 0.1)
				(type default)
			)
			(layer "F.Fab")
		)
		(fp_line
			(start -0.12065 0.2794)
			(end -0.12065 0.3048)
			(stroke
				(width 0.1)
				(type default)
			)
			(layer "F.Fab")
		)
		(fp_line
			(start 0.120396 0.2794)
			(end -0.12065 0.2794)
			(stroke
				(width 0.1)
				(type default)
			)
			(layer "F.Fab")
		)
		(fp_line
			(start -0.12065 -0.2794)
			(end 0.12065 -0.2794)
			(stroke
				(width 0.1)
				(type default)
			)
			(layer "F.Fab")
		)
		(fp_line
			(start 0.12065 -0.2794)
			(end 0.12065 -0.3048)
			(stroke
				(width 0.1)
				(type default)
			)
			(layer "F.Fab")
		)
		(fp_line
			(start 0.12065 -0.3048)
			(end 0.67945 -0.3048)
			(stroke
				(width 0.1)
				(type default)
			)
			(layer "F.Fab")
		)
		(fp_line
			(start 0.67945 -0.3048)
			(end 0.67945 0.3048)
			(stroke
				(width 0.1)
				(type default)
			)
			(layer "F.Fab")
		)
		(fp_line
			(start -0.67945 -0.305054)
			(end -0.12065 -0.305054)
			(stroke
				(width 0.1)
				(type default)
			)
			(layer "F.Fab")
		)
		(fp_line
			(start -0.12065 -0.305054)
			(end -0.12065 -0.2794)
			(stroke
				(width 0.1)
				(type default)
			)
			(layer "F.Fab")
		)
		(pad "1" smd circle
			(at -0.40005 0 270)
			(size 0 0)
			(layers "F.Cu" "F.Mask" "F.Paste")
			(net "GND")
		)
		(pad "2" smd circle
			(at 0.40005 0 270)
			(size 0 0)
			(layers "F.Cu" "F.Mask" "F.Paste")
			(net "P3V3_SSD1")
		)
	)
	(footprint ""
		(layer "F.Cu")
		(at 307.045868 -46.4439 180)
		(property "Reference" "U73"
			(at 0.467868 -2.45237 0)
			(unlocked yes)
			(layer "F.SilkS")
			(effects
				(font
					(size 0.7874 0.5842)
					(thickness 0.1524)
				)
			)
		)
		(property "Value" ""
			(at 0 0 180)
			(layer "F.Fab")
			(effects
				(font
					(size 1.27 1.27)
				)
			)
		)
		(duplicate_pad_numbers_are_jumpers no)
		(fp_line
			(start 1.500124 1.500124)
			(end 1.004062 1.500124)
			(stroke
				(width 0.1524)
				(type default)
			)
			(layer "F.SilkS")
		)
		(fp_line
			(start 1.500124 1.004062)
			(end 1.500124 1.500124)
			(stroke
				(width 0.1524)
				(type default)
			)
			(layer "F.SilkS")
		)
		(fp_line
			(start 1.500124 -1.500124)
			(end 1.500124 -1.004062)
			(stroke
				(width 0.1524)
				(type default)
			)
			(layer "F.SilkS")
		)
		(fp_line
			(start 1.004062 -1.500124)
			(end 1.500124 -1.500124)
			(stroke
				(width 0.1524)
				(type default)
			)
			(layer "F.SilkS")
		)
		(fp_line
			(start -1.004062 1.500124)
			(end -1.500124 1.500124)
			(stroke
				(width 0.1524)
				(type default)
			)
			(layer "F.SilkS")
		)
		(fp_line
			(start -1.500124 1.500124)
			(end -1.500124 1.004062)
			(stroke
				(width 0.1524)
				(type default)
			)
			(layer "F.SilkS")
		)
		(fp_line
			(start -1.500124 -1.004062)
			(end -1.500124 -1.500124)
			(stroke
				(width 0.1524)
				(type default)
			)
			(layer "F.SilkS")
		)
		(fp_line
			(start -1.500124 -1.500124)
			(end -1.004062 -1.500124)
			(stroke
				(width 0.1524)
				(type default)
			)
			(layer "F.SilkS")
		)
		(fp_poly
			(pts
				(xy -1.96977 -2.297684) (xy -2.688336 -1.579118) (xy -1.610614 -1.219962)
			)
			(stroke
				(width 0)
				(type default)
			)
			(fill yes)
			(layer "F.SilkS")
		)
		(fp_line
			(start 1.500124 1.500124)
			(end -1.500124 1.500124)
			(stroke
				(width 0.1)
				(type default)
			)
			(layer "F.Fab")
		)
		(fp_line
			(start 1.500124 -1.500124)
			(end 1.500124 1.500124)
			(stroke
				(width 0.1)
				(type default)
			)
			(layer "F.Fab")
		)
		(fp_line
			(start -1.500124 1.500124)
			(end -1.500124 -1.500124)
			(stroke
				(width 0.1)
				(type default)
			)
			(layer "F.Fab")
		)
		(fp_line
			(start -1.500124 -1.500124)
			(end 1.500124 -1.500124)
			(stroke
				(width 0.1)
				(type default)
			)
			(layer "F.Fab")
		)
		(fp_poly
			(pts
				(xy -2.847848 -1.258062) (xy -2.847848 -0.242062) (xy -1.831848 -0.750062)
			)
			(stroke
				(width 0)
				(type default)
			)
			(fill yes)
			(layer "F.Fab")
		)
		(pad "1" smd rect
			(at -1.400048 -0.750062 90)
			(size 0.2286 0.6096)
			(layers "F.Cu" "F.Mask" "F.Paste")
			(net "SSD10_ADC_A1")
		)
		(pad "2" smd rect
			(at -1.400048 -0.249936 90)
			(size 0.2286 0.6096)
			(layers "F.Cu" "F.Mask" "F.Paste")
			(net "SSD10_ADC_A0")
		)
		(pad "3" smd rect
			(at -1.400048 0.249936 90)
			(size 0.2286 0.6096)
			(layers "F.Cu" "F.Mask" "F.Paste")
			(net "SSD10_ADC_ALERT_N")
		)
		(pad "4" smd rect
			(at -1.400048 0.750062 90)
			(size 0.2286 0.6096)
			(layers "F.Cu" "F.Mask" "F.Paste")
			(net "SMB_SSD10_ADC_SDA")
		)
		(pad "5" smd rect
			(at -0.750062 1.400048 180)
			(size 0.2286 0.6096)
			(layers "F.Cu" "F.Mask" "F.Paste")
			(net "SMB_SSD10_ADC_SCL")
		)
		(pad "6" smd rect
			(at -0.249936 1.400048 180)
			(size 0.2286 0.6096)
			(layers "F.Cu" "F.Mask" "F.Paste")
			(net "Net_8702")
		)
		(pad "7" smd rect
			(at 0.249936 1.400048 180)
			(size 0.2286 0.6096)
			(layers "F.Cu" "F.Mask" "F.Paste")
			(net "Net_8701")
		)
		(pad "8" smd rect
			(at 0.750062 1.400048 180)
			(size 0.2286 0.6096)
			(layers "F.Cu" "F.Mask" "F.Paste")
			(net "Net_8700")
		)
		(pad "9" smd rect
			(at 1.400048 0.750062 90)
			(size 0.2286 0.6096)
			(layers "F.Cu" "F.Mask" "F.Paste")
			(net "P3V3_AUX")
		)
		(pad "10" smd rect
			(at 1.400048 0.249936 90)
			(size 0.2286 0.6096)
			(layers "F.Cu" "F.Mask" "F.Paste")
			(net "GND")
		)
		(pad "11" smd rect
			(at 1.400048 -0.249936 90)
			(size 0.2286 0.6096)
			(layers "F.Cu" "F.Mask" "F.Paste")
			(net "P12V_SSD10_R")
		)
		(pad "12" smd rect
			(at 1.400048 -0.750062 90)
			(size 0.2286 0.6096)
			(layers "F.Cu" "F.Mask" "F.Paste")
			(net "P12V_SSD10_VIN_N")
		)
		(pad "13" smd rect
			(at 0.750062 -1.400048 180)
			(size 0.2286 0.6096)
			(layers "F.Cu" "F.Mask" "F.Paste")
			(net "P12V_SSD10_VIN_P")
		)
		(pad "14" smd rect
			(at 0.249936 -1.400048 180)
			(size 0.2286 0.6096)
			(layers "F.Cu" "F.Mask" "F.Paste")
			(net "Net_8699")
		)
		(pad "15" smd rect
			(at -0.249936 -1.400048 180)
			(size 0.2286 0.6096)
			(layers "F.Cu" "F.Mask" "F.Paste")
			(net "Net_8698")
		)
		(pad "16" smd rect
			(at -0.750062 -1.400048 180)
			(size 0.2286 0.6096)
			(layers "F.Cu" "F.Mask" "F.Paste")
			(net "Net_8697")
		)
		(pad "TH" smd rect
			(at 0 0 180)
			(size 1.7018 1.7018)
			(layers "F.Cu" "F.Mask" "F.Paste")
			(net "GND")
		)
		(zone
			(layer "F.Cu")
			(hatch none 0.5)
			(connect_pads
				(clearance 0)
			)
			(min_thickness 0.25)
			(keepout
				(tracks not_allowed)
				(vias allowed)
				(pads allowed)
				(copperpour not_allowed)
				(footprints allowed)
			)
			(placement
				(enabled no)
				(sheetname "")
			)
			(fill
				(thermal_gap 0.5)
				(thermal_bridge_width 0.5)
				(island_removal_mode 0)
			)
			(polygon
				(pts
					(xy 308.090316 -46.4185) (xy 308.090316 -45.399452) (xy 306.00142 -45.399452) (xy 306.00142 -47.488348)
					(xy 308.090316 -47.488348) (xy 308.090316 -46.4439) (xy 307.947568 -46.4439) (xy 307.947568 -47.3456)
					(xy 306.144168 -47.3456) (xy 306.144168 -45.5422) (xy 307.947568 -45.5422) (xy 307.947568 -46.4185)
				)
			)
		)
	)
	(footprint ""
		(layer "F.Cu")
		(at 356.349808 -159.844994 180)
		(property "Reference" "PR7052"
			(at 0 0 180)
			(layer "F.SilkS")
			(hide yes)
			(effects
				(font
					(size 1.27 1.27)
				)
			)
		)
		(property "Value" ""
			(at 0 0 180)
			(layer "F.Fab")
			(effects
				(font
					(size 1.27 1.27)
				)
			)
		)
		(duplicate_pad_numbers_are_jumpers no)
		(fp_line
			(start 0.7874 0.4064)
			(end -0.7874 0.4064)
			(stroke
				(width 0.1524)
				(type default)
			)
			(layer "F.SilkS")
		)
		(fp_line
			(start 0.7874 -0.4064)
			(end 0.7874 0.4064)
			(stroke
				(width 0.1524)
				(type default)
			)
			(layer "F.SilkS")
		)
		(fp_line
			(start -0.7874 0.4064)
			(end -0.7874 -0.4064)
			(stroke
				(width 0.1524)
				(type default)
			)
			(layer "F.SilkS")
		)
		(fp_line
			(start -0.7874 -0.4064)
			(end 0.7874 -0.4064)
			(stroke
				(width 0.1524)
				(type default)
			)
			(layer "F.SilkS")
		)
		(fp_line
			(start 0.67945 0.3048)
			(end 0.120396 0.3048)
			(stroke
				(width 0.1)
				(type default)
			)
			(layer "F.Fab")
		)
		(fp_line
			(start 0.67945 -0.3048)
			(end 0.67945 0.3048)
			(stroke
				(width 0.1)
				(type default)
			)
			(layer "F.Fab")
		)
		(fp_line
			(start 0.12065 -0.2794)
			(end 0.12065 -0.3048)
			(stroke
				(width 0.1)
				(type default)
			)
			(layer "F.Fab")
		)
		(fp_line
			(start 0.12065 -0.3048)
			(end 0.67945 -0.3048)
			(stroke
				(width 0.1)
				(type default)
			)
			(layer "F.Fab")
		)
		(fp_line
			(start 0.120396 0.3048)
			(end 0.120396 0.2794)
			(stroke
				(width 0.1)
				(type default)
			)
			(layer "F.Fab")
		)
		(fp_line
			(start 0.120396 0.2794)
			(end -0.12065 0.2794)
			(stroke
				(width 0.1)
				(type default)
			)
			(layer "F.Fab")
		)
		(fp_line
			(start -0.12065 0.3048)
			(end -0.67945 0.3048)
			(stroke
				(width 0.1)
				(type default)
			)
			(layer "F.Fab")
		)
		(fp_line
			(start -0.12065 0.2794)
			(end -0.12065 0.3048)
			(stroke
				(width 0.1)
				(type default)
			)
			(layer "F.Fab")
		)
		(fp_line
			(start -0.12065 -0.2794)
			(end 0.12065 -0.2794)
			(stroke
				(width 0.1)
				(type default)
			)
			(layer "F.Fab")
		)
		(fp_line
			(start -0.12065 -0.305054)
			(end -0.12065 -0.2794)
			(stroke
				(width 0.1)
				(type default)
			)
			(layer "F.Fab")
		)
		(fp_line
			(start -0.67945 0.3048)
			(end -0.67945 -0.305054)
			(stroke
				(width 0.1)
				(type default)
			)
			(layer "F.Fab")
		)
		(fp_line
			(start -0.67945 -0.305054)
			(end -0.12065 -0.305054)
			(stroke
				(width 0.1)
				(type default)
			)
			(layer "F.Fab")
		)
		(pad "1" smd circle
			(at -0.40005 0 180)
			(size 0 0)
			(layers "F.Cu" "F.Mask" "F.Paste")
			(net "P12V_NIC6_CO_FLTB")
		)
		(pad "2" smd circle
			(at 0.40005 0 180)
			(size 0 0)
			(layers "F.Cu" "F.Mask" "F.Paste")
			(net "P3V3_AUX")
		)
	)
	(footprint ""
		(layer "F.Cu")
		(at 338.074 -169.037 180)
		(property "Reference" "R4770"
			(at 0 0 180)
			(layer "F.SilkS")
			(hide yes)
			(effects
				(font
					(size 1.27 1.27)
				)
			)
		)
		(property "Value" ""
			(at 0 0 180)
			(layer "F.Fab")
			(effects
				(font
					(size 1.27 1.27)
				)
			)
		)
		(duplicate_pad_numbers_are_jumpers no)
		(fp_line
			(start 0.7874 0.4064)
			(end -0.7874 0.4064)
			(stroke
				(width 0.1524)
				(type default)
			)
			(layer "F.SilkS")
		)
		(fp_line
			(start 0.7874 -0.4064)
			(end 0.7874 0.4064)
			(stroke
				(width 0.1524)
				(type default)
			)
			(layer "F.SilkS")
		)
		(fp_line
			(start -0.7874 0.4064)
			(end -0.7874 -0.4064)
			(stroke
				(width 0.1524)
				(type default)
			)
			(layer "F.SilkS")
		)
		(fp_line
			(start -0.7874 -0.4064)
			(end 0.7874 -0.4064)
			(stroke
				(width 0.1524)
				(type default)
			)
			(layer "F.SilkS")
		)
		(fp_line
			(start 0.67945 0.3048)
			(end 0.120396 0.3048)
			(stroke
				(width 0.1)
				(type default)
			)
			(layer "F.Fab")
		)
		(fp_line
			(start 0.67945 -0.3048)
			(end 0.67945 0.3048)
			(stroke
				(width 0.1)
				(type default)
			)
			(layer "F.Fab")
		)
		(fp_line
			(start 0.12065 -0.2794)
			(end 0.12065 -0.3048)
			(stroke
				(width 0.1)
				(type default)
			)
			(layer "F.Fab")
		)
		(fp_line
			(start 0.12065 -0.3048)
			(end 0.67945 -0.3048)
			(stroke
				(width 0.1)
				(type default)
			)
			(layer "F.Fab")
		)
		(fp_line
			(start 0.120396 0.3048)
			(end 0.120396 0.2794)
			(stroke
				(width 0.1)
				(type default)
			)
			(layer "F.Fab")
		)
		(fp_line
			(start 0.120396 0.2794)
			(end -0.12065 0.2794)
			(stroke
				(width 0.1)
				(type default)
			)
			(layer "F.Fab")
		)
		(fp_line
			(start -0.12065 0.3048)
			(end -0.67945 0.3048)
			(stroke
				(width 0.1)
				(type default)
			)
			(layer "F.Fab")
		)
		(fp_line
			(start -0.12065 0.2794)
			(end -0.12065 0.3048)
			(stroke
				(width 0.1)
				(type default)
			)
			(layer "F.Fab")
		)
		(fp_line
			(start -0.12065 -0.2794)
			(end 0.12065 -0.2794)
			(stroke
				(width 0.1)
				(type default)
			)
			(layer "F.Fab")
		)
		(fp_line
			(start -0.12065 -0.305054)
			(end -0.12065 -0.2794)
			(stroke
				(width 0.1)
				(type default)
			)
			(layer "F.Fab")
		)
		(fp_line
			(start -0.67945 0.3048)
			(end -0.67945 -0.305054)
			(stroke
				(width 0.1)
				(type default)
			)
			(layer "F.Fab")
		)
		(fp_line
			(start -0.67945 -0.305054)
			(end -0.12065 -0.305054)
			(stroke
				(width 0.1)
				(type default)
			)
			(layer "F.Fab")
		)
		(pad "1" smd circle
			(at -0.40005 0 180)
			(size 0 0)
			(layers "F.Cu" "F.Mask" "F.Paste")
			(net "RST_PEX_SSD10_PERST_N")
		)
		(pad "2" smd circle
			(at 0.40005 0 180)
			(size 0 0)
			(layers "F.Cu" "F.Mask" "F.Paste")
			(net "RST_PEX_SSD10_PERST_R_N")
		)
	)
)
